(kicad_pcb
	(version 20260206)
	(generator "pcbnew")
	(generator_version "10.0")
	(general
		(thickness 1.6)
		(legacy_teardrops no)
	)
	(paper "A4")
	(title_block
		(title "pdpb — Lightning_PDPB_BRD.brd")
		(comment 1 "Lightning (Wiwynn / Facebook NVMe JBOF) / footprints 591-591 of 1140")
	)
	(layers
		(0 "F.Cu" signal "TOP")
		(4 "In1.Cu" signal "L2GND")
		(6 "In2.Cu" signal "L3")
		(8 "In3.Cu" signal "L4VCC")
		(10 "In4.Cu" signal "L5VCC")
		(12 "In5.Cu" signal "L6")
		(14 "In6.Cu" signal "L7GND")
		(2 "B.Cu" signal "BOTTOM")
		(9 "F.Adhes" user "F.Adhesive")
		(11 "B.Adhes" user "B.Adhesive")
		(13 "F.Paste" user "Package Geometry/Pastemask Top")
		(15 "B.Paste" user "Package Geometry/Pastemask Bottom")
		(5 "F.SilkS" user "Ref Des/Silkscreen Top")
		(7 "B.SilkS" user "Ref Des/Silkscreen Bottom")
		(1 "F.Mask" user "Board Geometry/Soldermask Top")
		(3 "B.Mask" user "Board Geometry/Soldermask Bottom")
		(17 "Dwgs.User" user "User.Drawings")
		(19 "Cmts.User" user "User.Comments")
		(21 "Eco1.User" user "User.Eco1")
		(23 "Eco2.User" user "User.Eco2")
		(25 "Edge.Cuts" user "Board Geometry/Outline")
		(27 "Margin" user)
		(31 "F.CrtYd" user "Package Geometry/Place Bound Top")
		(29 "B.CrtYd" user "Package Geometry/Place Bound Bottom")
		(35 "F.Fab" user "Ref Des/Assembly Top")
		(33 "B.Fab" user "Ref Des/Assembly Bottom")
	)
	(footprint ""
		(layer "F.Cu")
		(at 44.577 -13.081 90)
		(property "Reference" "U23"
			(at 0 0 90)
			(layer "F.SilkS")
			(hide yes)
			(effects
				(font
					(size 1.27 1.27)
				)
			)
		)
		(property "Value" "P2003EVG-GP"
			(at 0 -11.1252 90)
			(unlocked yes)
			(layer "F.Fab")
			(hide yes)
			(effects
				(font
					(size 1.016 1.016)
					(thickness 0.1524)
				)
			)
		)
		(property "Device Type" "SOIC8H79"
			(at 0 -12.6492 90)
			(unlocked yes)
			(layer "F.Fab")
			(hide yes)
			(effects
				(font
					(size 1.016 1.016)
					(thickness 0.1524)
				)
			)
		)
		(duplicate_pad_numbers_are_jumpers no)
		(fp_line
			(start 2.1336 -1.4224)
			(end -2.7432 -1.4224)
			(stroke
				(width 0.1524)
				(type default)
			)
			(layer "F.SilkS")
		)
		(fp_line
			(start -2.7432 -1.4224)
			(end -2.7432 1.4224)
			(stroke
				(width 0.1524)
				(type default)
			)
			(layer "F.SilkS")
		)
		(fp_line
			(start -2.7432 -0.508)
			(end -2.2352 0)
			(stroke
				(width 0.1524)
				(type default)
			)
			(layer "F.SilkS")
		)
		(fp_line
			(start -2.2352 0)
			(end -2.7432 0.508)
			(stroke
				(width 0.1524)
				(type default)
			)
			(layer "F.SilkS")
		)
		(fp_line
			(start 2.1336 1.4224)
			(end 2.1336 -1.4224)
			(stroke
				(width 0.1524)
				(type default)
			)
			(layer "F.SilkS")
		)
		(fp_line
			(start -2.7432 1.4224)
			(end 2.1336 1.4224)
			(stroke
				(width 0.1524)
				(type default)
			)
			(layer "F.SilkS")
		)
		(fp_line
			(start -2.6162 3.429)
			(end -2.6162 1.4732)
			(stroke
				(width 0.4064)
				(type default)
			)
			(layer "F.SilkS")
		)
		(fp_poly
			(pts
				(xy 2.2098 -1.4224) (xy 2.2098 1.4224) (xy -2.2225 1.4224) (xy -2.2225 -1.4224)
			)
			(stroke
				(width 0)
				(type default)
			)
			(fill yes)
			(layer "F.SilkS")
		)
		(fp_rect
			(start -2.4511 2.9972)
			(end 2.4511 -2.9972)
			(stroke
				(width 0)
				(type default)
			)
			(fill no)
			(layer "F.CrtYd")
		)
		(fp_poly
			(pts
				(xy -2.8194 3.6322) (xy -2.8194 -3.6322) (xy 2.8194 -3.6322) (xy 2.8194 -2.2987) (xy 2.4511 -2.2987)
				(xy 2.4511 -2.9972) (xy -2.4511 -2.9972) (xy -2.4511 2.9972) (xy 2.4511 2.9972) (xy 2.4511 -2.286)
				(xy 2.8194 -2.286) (xy 2.8194 3.6322)
			)
			(stroke
				(width 0)
				(type default)
			)
			(fill no)
			(layer "F.CrtYd")
		)
		(fp_rect
			(start -2.8194 3.6322)
			(end 2.8194 -3.6322)
			(stroke
				(width 0)
				(type default)
			)
			(fill no)
			(layer "F.Fab")
		)
		(pad "1" smd rect
			(at -1.905 2.54 90)
			(size 0.635 1.651)
			(layers "F.Cu" "F.Mask" "F.Paste")
			(net "P12V")
		)
		(pad "2" smd rect
			(at -0.635 2.54 90)
			(size 0.635 1.651)
			(layers "F.Cu" "F.Mask" "F.Paste")
			(net "P12V")
		)
		(pad "3" smd rect
			(at 0.635 2.54 90)
			(size 0.635 1.651)
			(layers "F.Cu" "F.Mask" "F.Paste")
			(net "P12V")
		)
		(pad "4" smd rect
			(at 1.905 2.54 90)
			(size 0.635 1.651)
			(layers "F.Cu" "F.Mask" "F.Paste")
			(net "SW_SSD14_N")
		)
		(pad "5" smd rect
			(at 1.905 -2.54 90)
			(size 0.635 1.651)
			(layers "F.Cu" "F.Mask" "F.Paste")
			(net "P12V_SSD14")
		)
		(pad "6" smd rect
			(at 0.635 -2.54 90)
			(size 0.635 1.651)
			(layers "F.Cu" "F.Mask" "F.Paste")
			(net "P12V_SSD14")
		)
		(pad "7" smd rect
			(at -0.635 -2.54 90)
			(size 0.635 1.651)
			(layers "F.Cu" "F.Mask" "F.Paste")
			(net "P12V_SSD14")
		)
		(pad "8" smd rect
			(at -1.905 -2.54 90)
			(size 0.635 1.651)
			(layers "F.Cu" "F.Mask" "F.Paste")
			(net "P12V_SSD14")
		)
	)
)
